(kicad_pcb
	(version 20260206)
	(generator "pcbnew")
	(generator_version "10.0")
	(general
		(thickness 1.6)
		(legacy_teardrops no)
	)
	(paper "A4")
	(title_block
		(title "v1-chassis-manager — T6M_CM_d_v01_1031_1645.brd")
		(comment 1 "Open CloudServer (Microsoft) / footprints 771-780 of 2512")
	)
	(layers
		(0 "F.Cu" signal "TOP")
		(4 "In1.Cu" signal "GND1")
		(6 "In2.Cu" signal "IN1")
		(8 "In3.Cu" signal "VCC1")
		(10 "In4.Cu" signal "VCC2")
		(12 "In5.Cu" signal "GND2")
		(14 "In6.Cu" signal "IN2")
		(16 "In7.Cu" signal "IN3")
		(18 "In8.Cu" signal "GND3")
		(2 "B.Cu" signal "BOTTOM")
		(9 "F.Adhes" user "F.Adhesive")
		(11 "B.Adhes" user "B.Adhesive")
		(13 "F.Paste" user "Package Geometry/Pastemask Top")
		(15 "B.Paste" user "Package Geometry/Pastemask Bottom")
		(5 "F.SilkS" user "Ref Des/Silkscreen Top")
		(7 "B.SilkS" user "Ref Des/Silkscreen Bottom")
		(1 "F.Mask" user "Board Geometry/Soldermask Top")
		(3 "B.Mask" user "Board Geometry/Soldermask Bottom")
		(17 "Dwgs.User" user "User.Drawings")
		(19 "Cmts.User" user "User.Comments")
		(21 "Eco1.User" user "User.Eco1")
		(23 "Eco2.User" user "User.Eco2")
		(25 "Edge.Cuts" user "Board Geometry/Outline")
		(27 "Margin" user)
		(31 "F.CrtYd" user "Package Geometry/Place Bound Top")
		(29 "B.CrtYd" user "Package Geometry/Place Bound Bottom")
		(35 "F.Fab" user "Ref Des/Assembly Top")
		(33 "B.Fab" user "Ref Des/Assembly Bottom")
	)
	(footprint ""
		(layer "F.Cu")
		(at 166.715694 -122.66422 180)
		(property "Reference" "R1042"
			(at 2.798064 -9.851644 0)
			(unlocked yes)
			(layer "F.SilkS")
			(effects
				(font
					(size 0.7874 0.5842)
					(thickness 0.1524)
				)
				(justify left)
			)
		)
		(property "Value" ""
			(at 0 0 180)
			(layer "F.Fab")
			(effects
				(font
					(size 1.27 1.27)
				)
			)
		)
		(duplicate_pad_numbers_are_jumpers no)
		(fp_line
			(start 0.7874 0.4064)
			(end -0.7874 0.4064)
			(stroke
				(width 0.1524)
				(type default)
			)
			(layer "F.SilkS")
		)
		(fp_line
			(start 0.7874 -0.4064)
			(end 0.7874 0.4064)
			(stroke
				(width 0.1524)
				(type default)
			)
			(layer "F.SilkS")
		)
		(fp_line
			(start -0.7874 0.4064)
			(end -0.7874 -0.4064)
			(stroke
				(width 0.1524)
				(type default)
			)
			(layer "F.SilkS")
		)
		(fp_line
			(start -0.7874 -0.4064)
			(end 0.7874 -0.4064)
			(stroke
				(width 0.1524)
				(type default)
			)
			(layer "F.SilkS")
		)
		(fp_poly
			(pts
				(xy -0.508 0.2794) (xy -0.508 0.2286) (xy -0.635 0.2286) (xy -0.635 -0.254) (xy -0.5334 -0.254)
				(xy -0.5334 -0.2794) (xy 0.5334 -0.2794) (xy 0.5334 -0.254) (xy 0.635 -0.254) (xy 0.635 0.254) (xy 0.5334 0.254)
				(xy 0.5334 0.2794)
			)
			(stroke
				(width 0)
				(type default)
			)
			(fill no)
			(layer "F.CrtYd")
		)
		(pad "1" smd rect
			(at 0.40005 0 180)
			(size 0.4572 0.508)
			(layers "F.Cu" "F.Mask" "F.Paste")
			(net "FM_NODE1_DDR3_DRAM_POK_R_L")
		)
		(pad "2" smd rect
			(at -0.40005 0 180)
			(size 0.4572 0.508)
			(layers "F.Cu" "F.Mask" "F.Paste")
			(net "FM_NODE1_DDR3_DRAM_POK_L")
		)
	)
	(footprint ""
		(layer "F.Cu")
		(at 152.755854 -136.171432)
		(property "Reference" "R1062"
			(at -5.190236 1.951482 0)
			(unlocked yes)
			(layer "F.SilkS")
			(effects
				(font
					(size 0.7874 0.5842)
					(thickness 0.1524)
				)
				(justify left)
			)
		)
		(property "Value" ""
			(at 0 0 0)
			(layer "F.Fab")
			(effects
				(font
					(size 1.27 1.27)
				)
			)
		)
		(duplicate_pad_numbers_are_jumpers no)
		(fp_line
			(start -0.7874 -0.4064)
			(end 0.7874 -0.4064)
			(stroke
				(width 0.1524)
				(type default)
			)
			(layer "F.SilkS")
		)
		(fp_line
			(start -0.7874 0.4064)
			(end -0.7874 -0.4064)
			(stroke
				(width 0.1524)
				(type default)
			)
			(layer "F.SilkS")
		)
		(fp_line
			(start 0.7874 -0.4064)
			(end 0.7874 0.4064)
			(stroke
				(width 0.1524)
				(type default)
			)
			(layer "F.SilkS")
		)
		(fp_line
			(start 0.7874 0.4064)
			(end -0.7874 0.4064)
			(stroke
				(width 0.1524)
				(type default)
			)
			(layer "F.SilkS")
		)
		(fp_poly
			(pts
				(xy -0.508 0.2794) (xy -0.508 0.2286) (xy -0.635 0.2286) (xy -0.635 -0.254) (xy -0.5334 -0.254)
				(xy -0.5334 -0.2794) (xy 0.5334 -0.2794) (xy 0.5334 -0.254) (xy 0.635 -0.254) (xy 0.635 0.254) (xy 0.5334 0.254)
				(xy 0.5334 0.2794)
			)
			(stroke
				(width 0)
				(type default)
			)
			(fill no)
			(layer "F.CrtYd")
		)
		(pad "1" smd rect
			(at 0.40005 0)
			(size 0.4572 0.508)
			(layers "F.Cu" "F.Mask" "F.Paste")
			(net "RST_BTN_L")
		)
		(pad "2" smd rect
			(at -0.40005 0)
			(size 0.4572 0.508)
			(layers "F.Cu" "F.Mask" "F.Paste")
			(net "P3V3_STB_NODE1")
		)
	)
	(footprint ""
		(layer "F.Cu")
		(at 82.038444 -118.645686 -90)
		(property "Reference" "TP175"
			(at 0 0 270)
			(layer "F.SilkS")
			(hide yes)
			(effects
				(font
					(size 1.27 1.27)
				)
			)
		)
		(property "Value" ""
			(at 0 0 270)
			(layer "F.Fab")
			(effects
				(font
					(size 1.27 1.27)
				)
			)
		)
		(duplicate_pad_numbers_are_jumpers no)
		(fp_poly
			(pts
				(arc
					(start 0 0.3302)
					(mid 0 -0.3302)
					(end 0 0.3302)
				)
			)
			(stroke
				(width 0)
				(type default)
			)
			(fill no)
			(layer "B.CrtYd")
		)
		(pad "1" thru_hole circle
			(at 0 0 270)
			(size 0.508 0.508)
			(drill 0.254)
			(layers "*.Cu" "*.Mask")
			(remove_unused_layers no)
			(net "N53313175")
			(clearance 0.127)
			(thermal_gap 0.127)
			(padstack
				(mode front_inner_back)
				(layer "Inner"
					(shape circle)
					(size 0.508 0.508)
					(clearance 0.127)
				)
				(layer "B.Cu"
					(shape circle)
					(size 0.6604 0.6604)
					(clearance 0.0508)
				)
			)
		)
	)
	(footprint ""
		(layer "F.Cu")
		(at 163.152328 -82.549492 180)
		(property "Reference" "PC28"
			(at -3.539744 0.125222 0)
			(unlocked yes)
			(layer "F.SilkS")
			(effects
				(font
					(size 0.7874 0.5842)
					(thickness 0.1524)
				)
				(justify left)
			)
		)
		(property "Value" ""
			(at 0 0 180)
			(layer "F.Fab")
			(effects
				(font
					(size 1.27 1.27)
				)
			)
		)
		(duplicate_pad_numbers_are_jumpers no)
		(fp_line
			(start 1.905 0.8636)
			(end -1.905 0.8636)
			(stroke
				(width 0.1524)
				(type default)
			)
			(layer "F.SilkS")
		)
		(fp_line
			(start 1.905 -0.8636)
			(end 1.905 0.8636)
			(stroke
				(width 0.1524)
				(type default)
			)
			(layer "F.SilkS")
		)
		(fp_line
			(start 0 0.8382)
			(end 0 -0.8382)
			(stroke
				(width 0.1524)
				(type default)
			)
			(layer "F.SilkS")
		)
		(fp_line
			(start -1.905 0.8636)
			(end -1.905 -0.8636)
			(stroke
				(width 0.1524)
				(type default)
			)
			(layer "F.SilkS")
		)
		(fp_line
			(start -1.905 -0.8636)
			(end 1.905 -0.8636)
			(stroke
				(width 0.1524)
				(type default)
			)
			(layer "F.SilkS")
		)
		(fp_rect
			(start -1.524 0.7366)
			(end 1.524 -0.7366)
			(stroke
				(width 0)
				(type default)
			)
			(fill no)
			(layer "F.CrtYd")
		)
		(pad "1" smd rect
			(at 0.94996 0 180)
			(size 1.1176 1.3716)
			(layers "F.Cu" "F.Mask" "F.Paste")
			(net "P1V0_NODE1")
		)
		(pad "2" smd rect
			(at -0.94996 0 180)
			(size 1.1176 1.3716)
			(layers "F.Cu" "F.Mask" "F.Paste")
			(net "GND")
		)
	)
	(footprint ""
		(layer "F.Cu")
		(at 117.68836 -164.631624 -90)
		(property "Reference" "U61"
			(at 48.179736 -32.1818 0)
			(unlocked yes)
			(layer "F.SilkS")
			(effects
				(font
					(size 0.7874 0.5842)
					(thickness 0.1524)
				)
				(justify left)
			)
		)
		(property "Value" ""
			(at 0 0 270)
			(layer "F.Fab")
			(effects
				(font
					(size 1.27 1.27)
				)
			)
		)
		(duplicate_pad_numbers_are_jumpers no)
		(fp_line
			(start -2.5654 2.0066)
			(end -2.5654 0.5842)
			(stroke
				(width 0.1524)
				(type default)
			)
			(layer "F.SilkS")
		)
		(fp_line
			(start 2.5654 2.0066)
			(end -2.5654 2.0066)
			(stroke
				(width 0.1524)
				(type default)
			)
			(layer "F.SilkS")
		)
		(fp_line
			(start -2.5654 0.5842)
			(end -1.9812 0)
			(stroke
				(width 0.1524)
				(type default)
			)
			(layer "F.SilkS")
		)
		(fp_line
			(start -1.9812 0)
			(end -2.5654 -0.5842)
			(stroke
				(width 0.1524)
				(type default)
			)
			(layer "F.SilkS")
		)
		(fp_line
			(start -2.5654 -0.5842)
			(end -2.5654 -2.0066)
			(stroke
				(width 0.1524)
				(type default)
			)
			(layer "F.SilkS")
		)
		(fp_line
			(start -2.5654 -2.0066)
			(end 2.5654 -2.0066)
			(stroke
				(width 0.1524)
				(type default)
			)
			(layer "F.SilkS")
		)
		(fp_line
			(start 2.5654 -2.0066)
			(end 2.5654 2.0066)
			(stroke
				(width 0.1524)
				(type default)
			)
			(layer "F.SilkS")
		)
		(fp_circle
			(center -2.032 1.524)
			(end -2.032 1.27)
			(stroke
				(width 0.1524)
				(type default)
			)
			(fill no)
			(layer "F.SilkS")
		)
		(fp_rect
			(start -2.5654 3.6703)
			(end 2.5654 -3.6703)
			(stroke
				(width 0)
				(type default)
			)
			(fill no)
			(layer "F.CrtYd")
		)
		(pad "1" smd rect
			(at -2.275078 2.921 270)
			(size 0.3556 1.4986)
			(layers "F.Cu" "F.Mask" "F.Paste")
			(net "PSU1_HUB_EN")
		)
		(pad "2" smd rect
			(at -1.625092 2.921 270)
			(size 0.3556 1.4986)
			(layers "F.Cu" "F.Mask" "F.Paste")
			(net "PSU2_HUB_EN")
		)
		(pad "3" smd rect
			(at -0.975106 2.921 270)
			(size 0.3556 1.4986)
			(layers "F.Cu" "F.Mask" "F.Paste")
			(net "UART3_RESET_N")
		)
		(pad "4" smd rect
			(at -0.32512 2.921 270)
			(size 0.3556 1.4986)
			(layers "F.Cu" "F.Mask" "F.Paste")
			(net "GND")
		)
		(pad "5" smd rect
			(at 0.32512 2.921 270)
			(size 0.3556 1.4986)
			(layers "F.Cu" "F.Mask" "F.Paste")
			(net "PSU3_HUB_EN")
		)
		(pad "6" smd rect
			(at 0.975106 2.921 270)
			(size 0.3556 1.4986)
			(layers "F.Cu" "F.Mask" "F.Paste")
			(net "PCA9535_INT_N")
		)
		(pad "7" smd rect
			(at 1.625092 2.921 270)
			(size 0.3556 1.4986)
			(layers "F.Cu" "F.Mask" "F.Paste")
			(net "I2C_COM3_SDA_RC")
		)
		(pad "8" smd rect
			(at 2.275078 2.921 270)
			(size 0.3556 1.4986)
			(layers "F.Cu" "F.Mask" "F.Paste")
			(net "I2C_COM3_SCL")
		)
		(pad "9" smd rect
			(at 2.275078 -2.921 270)
			(size 0.3556 1.4986)
			(layers "F.Cu" "F.Mask" "F.Paste")
			(net "UART_CMC_TX_P")
		)
		(pad "10" smd rect
			(at 1.625092 -2.921 270)
			(size 0.3556 1.4986)
			(layers "F.Cu" "F.Mask" "F.Paste")
			(net "UART_CMC_RX_P")
		)
		(pad "11" smd rect
			(at 0.975106 -2.921 270)
			(size 0.3556 1.4986)
			(layers "F.Cu" "F.Mask" "F.Paste")
			(net "CMC_CPU_RST_N")
		)
		(pad "12" smd rect
			(at 0.32512 -2.921 270)
			(size 0.3556 1.4986)
			(layers "F.Cu" "F.Mask" "F.Paste")
			(net "P3V3_NODE1")
		)
		(pad "13" smd rect
			(at -0.32512 -2.921 270)
			(size 0.3556 1.4986)
			(layers "F.Cu" "F.Mask" "F.Paste")
			(net "COM3_WAKEUP")
		)
		(pad "14" smd rect
			(at -0.975106 -2.921 270)
			(size 0.3556 1.4986)
			(layers "F.Cu" "F.Mask" "F.Paste")
			(net "CPLD_WDT1_R")
		)
		(pad "15" smd rect
			(at -1.625092 -2.921 270)
			(size 0.3556 1.4986)
			(layers "F.Cu" "F.Mask" "F.Paste")
			(net "FAN_MAX_CTRL")
		)
		(pad "16" smd rect
			(at -2.275078 -2.921 270)
			(size 0.3556 1.4986)
			(layers "F.Cu" "F.Mask" "F.Paste")
			(net "CMC_CPLD_RSV1")
		)
	)
	(footprint ""
		(layer "F.Cu")
		(at 151.113998 -155.33243 180)
		(property "Reference" "C435"
			(at -0.918972 1.004824 0)
			(unlocked yes)
			(layer "F.SilkS")
			(effects
				(font
					(size 0.7874 0.5842)
					(thickness 0.1524)
				)
				(justify left)
			)
		)
		(property "Value" ""
			(at 0 0 180)
			(layer "F.Fab")
			(effects
				(font
					(size 1.27 1.27)
				)
			)
		)
		(duplicate_pad_numbers_are_jumpers no)
		(fp_line
			(start 0.7874 0.4064)
			(end -0.7874 0.4064)
			(stroke
				(width 0.1524)
				(type default)
			)
			(layer "F.SilkS")
		)
		(fp_line
			(start 0.7874 -0.4064)
			(end 0.7874 0.4064)
			(stroke
				(width 0.1524)
				(type default)
			)
			(layer "F.SilkS")
		)
		(fp_line
			(start 0 0.381)
			(end 0 -0.381)
			(stroke
				(width 0.1524)
				(type default)
			)
			(layer "F.SilkS")
		)
		(fp_line
			(start -0.7874 0.4064)
			(end -0.7874 -0.4064)
			(stroke
				(width 0.1524)
				(type default)
			)
			(layer "F.SilkS")
		)
		(fp_line
			(start -0.7874 -0.4064)
			(end 0.7874 -0.4064)
			(stroke
				(width 0.1524)
				(type default)
			)
			(layer "F.SilkS")
		)
		(fp_poly
			(pts
				(xy -0.5334 0.254) (xy -0.635 0.254) (xy -0.635 0.2286) (xy -0.635 -0.254) (xy -0.5334 -0.254) (xy -0.5334 -0.2794)
				(xy 0.5334 -0.2794) (xy 0.5334 -0.254) (xy 0.635 -0.254) (xy 0.635 0.254) (xy 0.5334 0.254) (xy 0.5334 0.2794)
				(xy -0.508 0.2794) (xy -0.5334 0.2794)
			)
			(stroke
				(width 0)
				(type default)
			)
			(fill no)
			(layer "F.CrtYd")
		)
		(pad "1" smd rect
			(at 0.40005 0 180)
			(size 0.4572 0.508)
			(layers "F.Cu" "F.Mask" "F.Paste")
			(net "P2E_CPU_NIC2_NODE1_RX_DP")
		)
		(pad "2" smd rect
			(at -0.40005 0 180)
			(size 0.4572 0.508)
			(layers "F.Cu" "F.Mask" "F.Paste")
			(net "PCIE_LAN2_RX_C_DP")
		)
	)
	(footprint ""
		(layer "F.Cu")
		(at 11.704828 -151.71039)
		(property "Reference" "C552"
			(at 2.89179 2.504186 90)
			(unlocked yes)
			(layer "F.SilkS")
			(effects
				(font
					(size 0.7874 0.5842)
					(thickness 0.1524)
				)
				(justify left)
			)
		)
		(property "Value" ""
			(at 0 0 0)
			(layer "F.Fab")
			(effects
				(font
					(size 1.27 1.27)
				)
			)
		)
		(duplicate_pad_numbers_are_jumpers no)
		(fp_line
			(start -0.7874 -0.4064)
			(end 0.7874 -0.4064)
			(stroke
				(width 0.1524)
				(type default)
			)
			(layer "F.SilkS")
		)
		(fp_line
			(start -0.7874 0.4064)
			(end -0.7874 -0.4064)
			(stroke
				(width 0.1524)
				(type default)
			)
			(layer "F.SilkS")
		)
		(fp_line
			(start 0 0.381)
			(end 0 -0.381)
			(stroke
				(width 0.1524)
				(type default)
			)
			(layer "F.SilkS")
		)
		(fp_line
			(start 0.7874 -0.4064)
			(end 0.7874 0.4064)
			(stroke
				(width 0.1524)
				(type default)
			)
			(layer "F.SilkS")
		)
		(fp_line
			(start 0.7874 0.4064)
			(end -0.7874 0.4064)
			(stroke
				(width 0.1524)
				(type default)
			)
			(layer "F.SilkS")
		)
		(fp_poly
			(pts
				(xy -0.5334 0.254) (xy -0.635 0.254) (xy -0.635 0.2286) (xy -0.635 -0.254) (xy -0.5334 -0.254) (xy -0.5334 -0.2794)
				(xy 0.5334 -0.2794) (xy 0.5334 -0.254) (xy 0.635 -0.254) (xy 0.635 0.254) (xy 0.5334 0.254) (xy 0.5334 0.2794)
				(xy -0.508 0.2794) (xy -0.5334 0.2794)
			)
			(stroke
				(width 0)
				(type default)
			)
			(fill no)
			(layer "F.CrtYd")
		)
		(pad "1" smd rect
			(at 0.40005 0)
			(size 0.4572 0.508)
			(layers "F.Cu" "F.Mask" "F.Paste")
			(net "N54310596")
		)
		(pad "2" smd rect
			(at -0.40005 0)
			(size 0.4572 0.508)
			(layers "F.Cu" "F.Mask" "F.Paste")
			(net "N54310598")
		)
	)
	(footprint ""
		(layer "F.Cu")
		(at 120.63222 -185.209942 -90)
		(property "Reference" "R869"
			(at -4.768088 -0.152908 90)
			(unlocked yes)
			(layer "F.SilkS")
			(effects
				(font
					(size 0.7874 0.5842)
					(thickness 0.1524)
				)
				(justify left)
			)
		)
		(property "Value" ""
			(at 0 0 270)
			(layer "F.Fab")
			(effects
				(font
					(size 1.27 1.27)
				)
			)
		)
		(duplicate_pad_numbers_are_jumpers no)
		(fp_line
			(start -0.7874 0.4064)
			(end -0.7874 -0.4064)
			(stroke
				(width 0.1524)
				(type default)
			)
			(layer "F.SilkS")
		)
		(fp_line
			(start 0.7874 0.4064)
			(end -0.7874 0.4064)
			(stroke
				(width 0.1524)
				(type default)
			)
			(layer "F.SilkS")
		)
		(fp_line
			(start -0.7874 -0.4064)
			(end 0.7874 -0.4064)
			(stroke
				(width 0.1524)
				(type default)
			)
			(layer "F.SilkS")
		)
		(fp_line
			(start 0.7874 -0.4064)
			(end 0.7874 0.4064)
			(stroke
				(width 0.1524)
				(type default)
			)
			(layer "F.SilkS")
		)
		(fp_poly
			(pts
				(xy -0.508 0.2794) (xy -0.508 0.2286) (xy -0.635 0.2286) (xy -0.635 -0.254) (xy -0.5334 -0.254)
				(xy -0.5334 -0.2794) (xy 0.5334 -0.2794) (xy 0.5334 -0.254) (xy 0.635 -0.254) (xy 0.635 0.254) (xy 0.5334 0.254)
				(xy 0.5334 0.2794)
			)
			(stroke
				(width 0)
				(type default)
			)
			(fill no)
			(layer "F.CrtYd")
		)
		(pad "1" smd rect
			(at 0.40005 0 270)
			(size 0.4572 0.508)
			(layers "F.Cu" "F.Mask" "F.Paste")
			(net "T8_NODE4_EN")
		)
		(pad "2" smd rect
			(at -0.40005 0 270)
			(size 0.4572 0.508)
			(layers "F.Cu" "F.Mask" "F.Paste")
			(net "T8_NODE4_EN_R")
		)
	)
	(footprint ""
		(layer "F.Cu")
		(at 149.411944 -43.664124)
		(property "Reference" "R1009"
			(at -2.3368 -2.962148 0)
			(unlocked yes)
			(layer "F.SilkS")
			(effects
				(font
					(size 0.7874 0.5842)
					(thickness 0.1524)
				)
				(justify left)
			)
		)
		(property "Value" ""
			(at 0 0 0)
			(layer "F.Fab")
			(effects
				(font
					(size 1.27 1.27)
				)
			)
		)
		(duplicate_pad_numbers_are_jumpers no)
		(fp_line
			(start -0.7874 -0.4064)
			(end 0.7874 -0.4064)
			(stroke
				(width 0.1524)
				(type default)
			)
			(layer "F.SilkS")
		)
		(fp_line
			(start -0.7874 0.4064)
			(end -0.7874 -0.4064)
			(stroke
				(width 0.1524)
				(type default)
			)
			(layer "F.SilkS")
		)
		(fp_line
			(start 0.7874 -0.4064)
			(end 0.7874 0.4064)
			(stroke
				(width 0.1524)
				(type default)
			)
			(layer "F.SilkS")
		)
		(fp_line
			(start 0.7874 0.4064)
			(end -0.7874 0.4064)
			(stroke
				(width 0.1524)
				(type default)
			)
			(layer "F.SilkS")
		)
		(fp_poly
			(pts
				(xy -0.508 0.2794) (xy -0.508 0.2286) (xy -0.635 0.2286) (xy -0.635 -0.254) (xy -0.5334 -0.254)
				(xy -0.5334 -0.2794) (xy 0.5334 -0.2794) (xy 0.5334 -0.254) (xy 0.635 -0.254) (xy 0.635 0.254) (xy 0.5334 0.254)
				(xy 0.5334 0.2794)
			)
			(stroke
				(width 0)
				(type default)
			)
			(fill no)
			(layer "F.CrtYd")
		)
		(pad "1" smd rect
			(at 0.40005 0)
			(size 0.4572 0.508)
			(layers "F.Cu" "F.Mask" "F.Paste")
			(net "P5V_NODE1")
		)
		(pad "2" smd rect
			(at -0.40005 0)
			(size 0.4572 0.508)
			(layers "F.Cu" "F.Mask" "F.Paste")
			(net "UART_TX_P1")
		)
	)
	(footprint ""
		(layer "F.Cu")
		(at 37.18052 -6.550914 -90)
		(property "Reference" "PR31"
			(at 1.42494 9.388602 90)
			(unlocked yes)
			(layer "F.SilkS")
			(effects
				(font
					(size 0.7874 0.5842)
					(thickness 0.1524)
				)
				(justify left)
			)
		)
		(property "Value" ""
			(at 0 0 270)
			(layer "F.Fab")
			(effects
				(font
					(size 1.27 1.27)
				)
			)
		)
		(duplicate_pad_numbers_are_jumpers no)
		(fp_line
			(start -0.7874 0.4064)
			(end -0.7874 -0.4064)
			(stroke
				(width 0.1524)
				(type default)
			)
			(layer "F.SilkS")
		)
		(fp_line
			(start 0.7874 0.4064)
			(end -0.7874 0.4064)
			(stroke
				(width 0.1524)
				(type default)
			)
			(layer "F.SilkS")
		)
		(fp_line
			(start -0.7874 -0.4064)
			(end 0.7874 -0.4064)
			(stroke
				(width 0.1524)
				(type default)
			)
			(layer "F.SilkS")
		)
		(fp_line
			(start 0.7874 -0.4064)
			(end 0.7874 0.4064)
			(stroke
				(width 0.1524)
				(type default)
			)
			(layer "F.SilkS")
		)
		(fp_poly
			(pts
				(xy -0.508 0.2794) (xy -0.508 0.2286) (xy -0.635 0.2286) (xy -0.635 -0.254) (xy -0.5334 -0.254)
				(xy -0.5334 -0.2794) (xy 0.5334 -0.2794) (xy 0.5334 -0.254) (xy 0.635 -0.254) (xy 0.635 0.254) (xy 0.5334 0.254)
				(xy 0.5334 0.2794)
			)
			(stroke
				(width 0)
				(type default)
			)
			(fill no)
			(layer "F.CrtYd")
		)
		(pad "1" smd rect
			(at 0.40005 0 270)
			(size 0.4572 0.508)
			(layers "F.Cu" "F.Mask" "F.Paste")
			(net "P3V3_STB_NODE1")
		)
		(pad "2" smd rect
			(at -0.40005 0 270)
			(size 0.4572 0.508)
			(layers "F.Cu" "F.Mask" "F.Paste")
			(net "PWRGD_NODE1_PVDDR_STB_PG")
		)
	)
)
